# S9S_MB_2U (Grand Teton) — schematic parts with pin connectivity, parts 1596–1596 of 6093; source: Cadence DE-HDL packaged netlist (pstxprt.dat, pstxnet.dat, pstchip.dat)

J3  SCONN288_ADR50017P130CC  SCONN288_ADR50017-P130CC IO  pkg DDR288S_1-1VXB  page 84
  1  VIN_BULK0  POWER  = P12V_S3_AUX_CPU0_NVDIMM
  2  RFU0  TRI  = TP_CHB_CPU0_DIMM1_FRU_0
  3  VIN_MGMT  POWER  = P3V3_AUX
  4  HSCL  IN  = I3C_SPD_DDRABCD_CPU0_LVC1_SCL_2
  5  HSDA  BI  = I3C_SPD_DDRABCD_CPU0_LVC1_SDA
  6  VSS0  POWER  = GND
  7  DQ0_A  BI  = M_B_CPU0_SA_DQ<0>
  8  VSS1  POWER  = GND
  9  DQ1_A  BI  = M_B_CPU0_SA_DQ<1>
  10  VSS2  POWER  = GND
  11  DQS0_A_T  BI  = M_B_CPU0_SA_DQS_DP<0>
  12  DQS0_A_C  BI  = M_B_CPU0_SA_DQS_DN<0>
  13  VSS3  POWER  = GND
  14  DQ4_A  BI  = M_B_CPU0_SA_DQ<4>
  15  VSS4  POWER  = GND
  16  DQ5_A  BI  = M_B_CPU0_SA_DQ<5>
  17  VSS5  POWER  = GND
  18  DQ8_A  BI  = M_B_CPU0_SA_DQ<8>
  19  VSS6  POWER  = GND
  20  DQ9_A  BI  = M_B_CPU0_SA_DQ<9>
  21  VSS7  POWER  = GND
  22  DQS1_A_T  BI  = M_B_CPU0_SA_DQS_DP<1>
  23  DQS1_A_C  BI  = M_B_CPU0_SA_DQS_DN<1>
  24  VSS8  POWER  = GND
  25  DQ12_A  BI  = M_B_CPU0_SA_DQ<12>
  26  VSS9  POWER  = GND
  27  DQ13_A  BI  = M_B_CPU0_SA_DQ<13>
  28  VSS10  POWER  = GND
  29  DQ16_A  BI  = M_B_CPU0_SA_DQ<16>
  30  VSS11  POWER  = GND
  31  DQ17_A  BI  = M_B_CPU0_SA_DQ<17>
  32  VSS12  POWER  = GND
  33  DQS2_A_T  BI  = M_B_CPU0_SA_DQS_DP<2>
  34  DQS2_A_C  BI  = M_B_CPU0_SA_DQS_DN<2>
  35  VSS13  POWER  = GND
  36  DQ20_A  BI  = M_B_CPU0_SA_DQ<20>
  37  VSS14  POWER  = GND
  38  DQ21_A  BI  = M_B_CPU0_SA_DQ<21>
  39  VSS15  POWER  = GND
  40  DQ24_A  BI  = M_B_CPU0_SA_DQ<24>
  41  VSS16  POWER  = GND
  42  DQ25_A  BI  = M_B_CPU0_SA_DQ<25>
  43  VSS17  POWER  = GND
  44  DQS3_A_T  BI  = M_B_CPU0_SA_DQS_DP<3>
  45  DQS3_A_C  BI  = M_B_CPU0_SA_DQS_DN<3>
  46  VSS18  POWER  = GND
  47  DQ28_A  BI  = M_B_CPU0_SA_DQ<28>
  48  VSS19  POWER  = GND
  49  DQ29_A  BI  = M_B_CPU0_SA_DQ<29>
  50  VSS20  POWER  = GND
  51  CB0_A  BI  = M_B_CPU0_SA_CB<0>
  52  VSS21  POWER  = GND
  53  CB1_A  BI  = M_B_CPU0_SA_CB<1>
  54  VSS22  POWER  = GND
  55  DQS4_A_T  BI  = M_B_CPU0_SA_DQS_DP<4>
  56  DQS4_A_C  BI  = M_B_CPU0_SA_DQS_DN<4>
  57  VSS23  POWER  = GND
  58  CB4_A  BI  = M_B_CPU0_SA_CB<4>
  59  VSS24  POWER  = GND
  60  CB5_A  BI  = M_B_CPU0_SA_CB<5>
  61  VSS25  POWER  = GND
  62  ALERT_N  OUT  = M_B_CPU0_ALERT_N
  63  VSS26  POWER  = GND
  64  CS0_A_N  IN  = M_B_CPU0_SA_CS_N<0>
  65  VSS27  POWER  = GND
  66  CA0_A  IN  = M_B_CPU0_SA_CA<0>
  67  VSS28  POWER  = GND
  68  CA2_A  IN  = M_B_CPU0_SA_CA<2>
  69  VSS29  POWER  = GND
  70  CA4_A  IN  = M_B_CPU0_SA_CA<4>
  71  VSS30  POWER  = GND
  72  CA6_A  IN  = M_B_CPU0_SA_CA<6>
  73  VSS31  POWER  = GND
  74  PAR_A  IN  = M_B_CPU0_SA_PAR
  75  VSS32  POWER  = GND
  76  CA0_B  IN  = M_B_CPU0_SB_CA<0>
  77  VSS33  POWER  = GND
  78  CA2_B  IN  = M_B_CPU0_SB_CA<2>
  79  VSS34  POWER  = GND
  80  CA4_B  IN  = M_B_CPU0_SB_CA<4>
  81  VSS35  POWER  = GND
  82  CA6_B  IN  = M_B_CPU0_SB_CA<6>
  83  VSS36  POWER  = GND
  84  CS0_B_N  IN  = M_B_CPU0_SB_CS_N<0>
  85  VSS37  POWER  = GND
  86  \lbd||rsp_a_n\  OUT  = M_B_CPU0_SA_RSP<0>
  87  \lbs||rsp_b_n\  OUT  = M_B_CPU0_SB_RSP<0>
  88  VSS38  POWER  = GND
  89  CB4_B  BI  = M_B_CPU0_SB_CB<4>
  90  VSS39  POWER  = GND
  91  CB5_B  BI  = M_B_CPU0_SB_CB<5>
  92  VSS40  POWER  = GND
  93  \dqs9_b_t||tdqs9_b_t||dbi4_b_n\  BI  = M_B_CPU0_SB_DQS_DP<9>
  94  \dqs9_b_c||tdqs9_b_c\  BI  = M_B_CPU0_SB_DQS_DN<9>
  95  VSS41  POWER  = GND
  96  CB0_B  BI  = M_B_CPU0_SB_CB<0>
  97  VSS42  POWER  = GND
  98  CB1_B  BI  = M_B_CPU0_SB_CB<1>
  99  VSS43  POWER  = GND
  100  DQ0_B  BI  = M_B_CPU0_SB_DQ<0>
  101  VSS44  POWER  = GND
  102  DQ1_B  BI  = M_B_CPU0_SB_DQ<1>
  103  VSS45  POWER  = GND
  104  DQS0_B_T  BI  = M_B_CPU0_SB_DQS_DP<0>
  105  DQS0_B_C  BI  = M_B_CPU0_SB_DQS_DN<0>
  106  VSS46  POWER  = GND
  107  DQ4_B  BI  = M_B_CPU0_SB_DQ<4>
  108  VSS47  POWER  = GND
  109  DQ5_B  BI  = M_B_CPU0_SB_DQ<5>
  110  VSS48  POWER  = GND
  111  DQ8_B  BI  = M_B_CPU0_SB_DQ<8>
  112  VSS49  POWER  = GND
  113  DQ9_B  BI  = M_B_CPU0_SB_DQ<9>
  114  VSS50  POWER  = GND
  115  DQS1_B_T  BI  = M_B_CPU0_SB_DQS_DP<1>
  116  DQS1_B_C  BI  = M_B_CPU0_SB_DQS_DN<1>
  117  VSS51  POWER  = GND
  118  DQ12_B  BI  = M_B_CPU0_SB_DQ<12>
  119  VSS52  POWER  = GND
  120  DQ13_B  BI  = M_B_CPU0_SB_DQ<13>
  121  VSS53  POWER  = GND
  122  DQ16_B  BI  = M_B_CPU0_SB_DQ<16>
  123  VSS54  POWER  = GND
  124  DQ17_B  BI  = M_B_CPU0_SB_DQ<17>
  125  VSS55  POWER  = GND
  126  DQS2_B_T  BI  = M_B_CPU0_SB_DQS_DP<2>
  127  DQS2_B_C  BI  = M_B_CPU0_SB_DQS_DN<2>
  128  VSS56  POWER  = GND
  129  DQ20_B  BI  = M_B_CPU0_SB_DQ<20>
  130  VSS57  POWER  = GND
  131  DQ21_B  BI  = M_B_CPU0_SB_DQ<21>
  132  VSS58  POWER  = GND
  133  DQ24_B  BI  = M_B_CPU0_SB_DQ<24>
  134  VSS59  POWER  = GND
  135  DQ25_B  BI  = M_B_CPU0_SB_DQ<25>
  136  VSS60  POWER  = GND
  137  DQS3_B_T  BI  = M_B_CPU0_SB_DQS_DP<3>
  138  DQS3_B_C  BI  = M_B_CPU0_SB_DQS_DN<3>
  139  VSS61  POWER  = GND
  140  DQ28_B  BI  = M_B_CPU0_SB_DQ<28>
  141  VSS62  POWER  = GND
  142  DQ29_B  BI  = M_B_CPU0_SB_DQ<29>
  143  VSS63  POWER  = GND
  144  RFU1  TRI  = TP_CHB_CPU0_DIMM1_FRU_1
  145  VIN_BULK1  POWER  = P12V_S3_AUX_CPU0_NVDIMM
  146  VIN_BULK2  POWER  = P12V_S3_AUX_CPU0_NVDIMM
  147  \pwr_good||fail_n\  BI  = PWRGD_CHB_CPU0_DIMM1
  148  HSA  IN  = PD_CHB_CPU0_DIMM1_SAA
  149  RFU2  TRI  = TP_CHB_CPU0_DIMM1_FRU_2
  150  RFU3  TRI  = TP_CHB_CPU0_DIMM1_FRU_3
  151  VSS64  POWER  = GND
  152  DQ2_A  BI  = M_B_CPU0_SA_DQ<2>
  153  VSS65  POWER  = GND
  154  DQ3_A  BI  = M_B_CPU0_SA_DQ<3>
  155  VSS66  POWER  = GND
  156  \dqs5_a_c||tdqs5_a_c||dqs5_a_t||tdqs5_a_t\  BI  = M_B_CPU0_SA_DQS_DN<5>
  157  \dqs5_a_t||tdqs5_a_t\  BI  = M_B_CPU0_SA_DQS_DP<5>
  158  VSS67  POWER  = GND
  159  DQ6_A  BI  = M_B_CPU0_SA_DQ<6>
  160  VSS68  POWER  = GND
  161  DQ7_A  BI  = M_B_CPU0_SA_DQ<7>
  162  VSS69  POWER  = GND
  163  DQ10_A  BI  = M_B_CPU0_SA_DQ<10>
  164  VSS70  POWER  = GND
  165  DQ11_A  BI  = M_B_CPU0_SA_DQ<11>
  166  VSS71  POWER  = GND
  167  \dqs6_a_c||tdqs6_a_c||dqs6_a_t||tdqs6_a_t\  BI  = M_B_CPU0_SA_DQS_DN<6>
  168  \dqs6_a_t||tdqs6_a_t\  BI  = M_B_CPU0_SA_DQS_DP<6>
  169  VSS72  POWER  = GND
  170  DQ14_A  BI  = M_B_CPU0_SA_DQ<14>
  171  VSS73  POWER  = GND
  172  DQ15_A  BI  = M_B_CPU0_SA_DQ<15>
  173  VSS74  POWER  = GND
  174  DQ18_A  BI  = M_B_CPU0_SA_DQ<18>
  175  VSS75  POWER  = GND
  176  DQ19_A  BI  = M_B_CPU0_SA_DQ<19>
  177  VSS76  POWER  = GND
  178  \dqs7_a_c||tdqs7_a_c\  BI  = M_B_CPU0_SA_DQS_DN<7>
  179  \dqs7_a_t||tdqs7_a_t\  BI  = M_B_CPU0_SA_DQS_DP<7>
  180  VSS77  POWER  = GND
  181  DQ22_A  BI  = M_B_CPU0_SA_DQ<22>
  182  VSS78  POWER  = GND
  183  DQ23_A  BI  = M_B_CPU0_SA_DQ<23>
  184  VSS79  POWER  = GND
  185  DQ26_A  BI  = M_B_CPU0_SA_DQ<26>
  186  VSS80  POWER  = GND
  187  DQ27_A  BI  = M_B_CPU0_SA_DQ<27>
  188  VSS81  POWER  = GND
  189  \dqs8_a_c||tdqs8_a_c\  BI  = M_B_CPU0_SA_DQS_DN<8>
  190  \dqs8_a_t||tdqs8_a_t\  BI  = M_B_CPU0_SA_DQS_DP<8>
  191  VSS82  POWER  = GND
  192  DQ30_A  BI  = M_B_CPU0_SA_DQ<30>
  193  VSS83  POWER  = GND
  194  DQ31_A  BI  = M_B_CPU0_SA_DQ<31>
  195  VSS84  POWER  = GND
  196  CB2_A  BI  = M_B_CPU0_SA_CB<2>
  197  VSS85  POWER  = GND
  198  CB3_A  BI  = M_B_CPU0_SA_CB<3>
  199  VSS86  POWER  = GND
  200  \dqs9_a_c||tdqs9_a_c\  BI  = M_B_CPU0_SA_DQS_DN<9>
  201  \dqs9_a_t||tdqs9_a_t\  BI  = M_B_CPU0_SA_DQS_DP<9>
  202  VSS87  POWER  = GND
  203  CB6_A  BI  = M_B_CPU0_SA_CB<6>
  204  VSS88  POWER  = GND
  205  CB7_A  BI  = M_B_CPU0_SA_CB<7>
  206  VSS89  POWER  = GND
  207  RESET_N  IN  = RST_M_AB_CPU0_FPGA_N
  208  VSS90  POWER  = GND
  209  CS1_A_N  IN  = M_B_CPU0_SA_CS_N<1>
  210  VSS91  POWER  = GND
  211  CA1_A  IN  = M_B_CPU0_SA_CA<1>
  212  VSS92  POWER  = GND
  213  CA3_A  IN  = M_B_CPU0_SA_CA<3>
  214  VSS93  POWER  = GND
  215  CA5_A  IN  = M_B_CPU0_SA_CA<5>
  216  VSS94  POWER  = GND
  217  CK_T  IN  = M_B_CPU0_CLK_DP<0>
  218  CK_C  IN  = M_B_CPU0_CLK_DN<0>
  219  VSS95  POWER  = GND
  220  RFU4  TRI  = TP_CHB_CPU0_DIMM1_FRU_4
  221  CA1_B  IN  = M_B_CPU0_SB_CA<1>
  222  VSS96  POWER  = GND
  223  CA3_B  IN  = M_B_CPU0_SB_CA<3>
  224  VSS97  POWER  = GND
  225  CA5_B  IN  = M_B_CPU0_SB_CA<5>
  226  VSS98  POWER  = GND
  227  PAR_B  IN  = M_B_CPU0_SB_PAR
  228  VSS99  POWER  = GND
  229  CS1_B_N  IN  = M_B_CPU0_SB_CS_N<1>
  230  VSS100  POWER  = GND
  231  RFU5  TRI  = TP_CHB_CPU0_DIMM1_FRU_5
  232  RFU6  TRI  = TP_CHB_CPU0_DIMM1_FRU_6
  233  VSS101  POWER  = GND
  234  CB6_B  BI  = M_B_CPU0_SB_CB<6>
  235  VSS102  POWER  = GND
  236  CB7_B  BI  = M_B_CPU0_SB_CB<7>
  237  VSS103  POWER  = GND
  238  DQS4_B_C  BI  = M_B_CPU0_SB_DQS_DN<4>
  239  DQS4_B_T  BI  = M_B_CPU0_SB_DQS_DP<4>
  240  VSS104  POWER  = GND
  241  CB2_B  BI  = M_B_CPU0_SB_CB<2>
  242  VSS105  POWER  = GND
  243  CB3_B  BI  = M_B_CPU0_SB_CB<3>
  244  VSS106  POWER  = GND
  245  DQ2_B  BI  = M_B_CPU0_SB_DQ<2>
  246  VSS107  POWER  = GND
  247  DQ3_B  BI  = M_B_CPU0_SB_DQ<3>
  248  VSS108  POWER  = GND
  249  \dqs5_b_c||tdqs5_b_c\  BI  = M_B_CPU0_SB_DQS_DN<5>
  250  \dqs5_b_t||tdqs5_b_t\  BI  = M_B_CPU0_SB_DQS_DP<5>
  251  VSS109  POWER  = GND
  252  DQ6_B  BI  = M_B_CPU0_SB_DQ<6>
  253  VSS110  POWER  = GND
  254  DQ7_B  BI  = M_B_CPU0_SB_DQ<7>
  255  VSS111  POWER  = GND
  256  DQ10_B  BI  = M_B_CPU0_SB_DQ<10>
  257  VSS112  POWER  = GND
  258  DQ11_B  BI  = M_B_CPU0_SB_DQ<11>
  259  VSS113  POWER  = GND
  260  \dqs6_b_c||tdqs6_b_c\  BI  = M_B_CPU0_SB_DQS_DN<6>
  261  \dqs6_b_t||tdqs6_b_t\  BI  = M_B_CPU0_SB_DQS_DP<6>
  262  VSS114  POWER  = GND
  263  DQ14_B  BI  = M_B_CPU0_SB_DQ<14>
  264  VSS115  POWER  = GND
  265  DQ15_B  BI  = M_B_CPU0_SB_DQ<15>
  266  VSS116  POWER  = GND
  267  DQ18_B  BI  = M_B_CPU0_SB_DQ<18>
  268  VSS117  POWER  = GND
  269  DQ19_B  BI  = M_B_CPU0_SB_DQ<19>
  270  VSS118  POWER  = GND
  271  \dqs7_b_c||tdqs7_b_c\  BI  = M_B_CPU0_SB_DQS_DN<7>
  272  \dqs7_b_t||tdqs7_b_t\  BI  = M_B_CPU0_SB_DQS_DP<7>
  273  VSS119  POWER  = GND
  274  DQ22_B  BI  = M_B_CPU0_SB_DQ<22>
  275  VSS120  POWER  = GND
  276  DQ23_B  BI  = M_B_CPU0_SB_DQ<23>
  277  VSS121  POWER  = GND
  278  DQ26_B  BI  = M_B_CPU0_SB_DQ<26>
  279  VSS122  POWER  = GND
  280  DQ27_B  BI  = M_B_CPU0_SB_DQ<27>
  281  VSS123  POWER  = GND
  282  \dqs8_b_c||tdqs8_b_c\  BI  = M_B_CPU0_SB_DQS_DN<8>
  283  \dqs8_b_t||tdqs8_b_t\  BI  = M_B_CPU0_SB_DQS_DP<8>
  284  VSS124  POWER  = GND
  285  DQ30_B  BI  = M_B_CPU0_SB_DQ<30>
  286  VSS125  POWER  = GND
  287  DQ31_B  BI  = M_B_CPU0_SB_DQ<31>
  288  VSS126  POWER  = GND
  G1  G1  POWER  = GND
  G2  G2  POWER  = GND
  G3  G3  POWER  = GND
